(kicad_pcb
	(version 20241229)
	(generator "pcbnew")
	(generator_version "9.0")
	(general
		(thickness 1.6296)
		(legacy_teardrops no)
	)
	(paper "A3")
	(title_block
		(title "Thunderbolt to 10GbE adapter")
		(date "2026-04-21")
		(rev "1.1.0")
		(company "Antmicro Ltd")
		(comment 1 "www.antmicro.com")
		(comment 9 "footprints 85-88 of 703")
	)
	(layers
		(0 "F.Cu" signal)
		(4 "In1.Cu" signal)
		(6 "In2.Cu" signal)
		(8 "In3.Cu" signal)
		(10 "In4.Cu" signal)
		(12 "In5.Cu" signal)
		(14 "In6.Cu" signal)
		(2 "B.Cu" signal)
		(9 "F.Adhes" user "F.Adhesive")
		(11 "B.Adhes" user "B.Adhesive")
		(13 "F.Paste" user)
		(15 "B.Paste" user)
		(5 "F.SilkS" user "F.Silkscreen")
		(7 "B.SilkS" user "B.Silkscreen")
		(1 "F.Mask" user)
		(3 "B.Mask" user)
		(17 "Dwgs.User" user "User.Drawings")
		(19 "Cmts.User" user "User.Comments")
		(21 "Eco1.User" user "User.Eco1")
		(23 "Eco2.User" user "User.Eco2")
		(25 "Edge.Cuts" user)
		(27 "Margin" user)
		(31 "F.CrtYd" user "F.Courtyard")
		(29 "B.CrtYd" user "B.Courtyard")
		(35 "F.Fab" user)
		(33 "B.Fab" user)
	)
	(footprint "antmicro-footprints:VQFN-HR-9_2x1.5mm"
		(layer "F.Cu")
		(at 154.450001 110.15)
		(property "Reference" "U11"
			(at 13.650003 17.049998 0)
			(layer "F.SilkS")
			(effects
				(font
					(size 0.7 0.7)
					(thickness 0.15)
				)
			)
		)
		(property "Value" "TPS566231P"
			(at -1.65 2.15 0)
			(layer "F.Fab")
			(effects
				(font
					(size 0.7 0.7)
					(thickness 0.15)
				)
				(justify left bottom)
			)
		)
		(property "Datasheet" "https://www.ti.com/lit/ds/symlink/tps566231.pdf"
			(at 0 -0.045 0)
			(layer "F.Fab")
			(effects
				(font
					(size 0.7 0.7)
					(thickness 0.15)
				)
				(justify left bottom)
			)
		)
		(property "Description" "Switching Voltage Regulators 3-V to 18-V, 6-A synchronous buck converter"
			(at -1.45 3.65 0)
			(layer "F.Fab")
			(effects
				(font
					(size 0.7 0.7)
					(thickness 0.15)
				)
				(justify left bottom)
			)
		)
		(property "Manufacturer" "Texas Instruments"
			(at 0 0 0)
			(unlocked yes)
			(layer "F.Fab")
			(hide yes)
			(effects
				(font
					(size 1 1)
					(thickness 0.15)
				)
			)
		)
		(property "MPN" "TPS566231PRQFR"
			(at 0 0 0)
			(unlocked yes)
			(layer "F.Fab")
			(hide yes)
			(effects
				(font
					(size 1 1)
					(thickness 0.15)
				)
			)
		)
		(property "Author" "Antmicro"
			(at 0 0 0)
			(unlocked yes)
			(layer "F.Fab")
			(hide yes)
			(effects
				(font
					(size 1 1)
					(thickness 0.15)
				)
			)
		)
		(property "License" "Apache-2.0"
			(at 0 0 0)
			(unlocked yes)
			(layer "F.Fab")
			(hide yes)
			(effects
				(font
					(size 1 1)
					(thickness 0.15)
				)
			)
		)
		(sheetname "/X710 DCDC converters/")
		(sheetfile "DCDC_converters_X710.kicad_sch")
		(attr smd)
		(fp_line
			(start -1 -0.945)
			(end -0.695 -0.945)
			(stroke
				(width 0.15)
				(type solid)
			)
			(layer "F.SilkS")
		)
		(fp_line
			(start -1 0.945)
			(end -0.695 0.945)
			(stroke
				(width 0.15)
				(type solid)
			)
			(layer "F.SilkS")
		)
		(fp_line
			(start 1 -0.945)
			(end 0.695 -0.945)
			(stroke
				(width 0.15)
				(type solid)
			)
			(layer "F.SilkS")
		)
		(fp_line
			(start 1 0.945)
			(end 0.2 0.945)
			(stroke
				(width 0.15)
				(type solid)
			)
			(layer "F.SilkS")
		)
		(fp_circle
			(center -1.18 -0.77)
			(end -1.13 -0.77)
			(stroke
				(width 0.15)
				(type solid)
			)
			(fill yes)
			(layer "F.SilkS")
		)
		(fp_rect
			(start -1.3 -1.05)
			(end 1.3 1.05)
			(stroke
				(width 0.05)
				(type solid)
			)
			(fill no)
			(layer "F.CrtYd")
		)
		(fp_rect
			(start -1 -0.75)
			(end 1 0.75)
			(stroke
				(width 0.15)
				(type solid)
			)
			(fill no)
			(layer "F.Fab")
		)
		(fp_text user "License: Apache-2.0"
			(at -1.65 5.75 0)
			(layer "F.Fab")
			(effects
				(font
					(size 0.7 0.7)
					(thickness 0.15)
				)
				(justify left bottom)
			)
		)
		(fp_text user "${REFERENCE}"
			(at -1.65 3.35 0)
			(layer "F.Fab")
			(effects
				(font
					(size 0.7 0.7)
					(thickness 0.15)
				)
				(justify left bottom)
			)
		)
		(fp_text user "Author: Antmicro"
			(at -1.65 4.55 0)
			(layer "F.Fab")
			(effects
				(font
					(size 0.7 0.7)
					(thickness 0.15)
				)
				(justify left bottom)
			)
		)
		(pad "1" smd roundrect
			(at -0.925 -0.5)
			(size 0.55 0.25)
			(layers "F.Cu" "F.Mask" "F.Paste")
			(roundrect_rratio 0.125)
			(net 108 "/X710 DCDC converters/1V88_VCC")
			(pinfunction "V_{CC}")
			(pintype "passive")
		)
		(pad "2" smd roundrect
			(at -0.925 0)
			(size 0.55 0.25)
			(layers "F.Cu" "F.Mask" "F.Paste")
			(roundrect_rratio 0.125)
			(net 337 "/X710 DCDC converters/1V88_FB")
			(pinfunction "FB")
			(pintype "input")
		)
		(pad "3" smd roundrect
			(at -0.925 0.5)
			(size 0.55 0.25)
			(layers "F.Cu" "F.Mask" "F.Paste")
			(roundrect_rratio 0.125)
			(net 384 "/X710 DCDC converters/1V88_EN")
			(pinfunction "EN")
			(pintype "input")
		)
		(pad "4" smd roundrect
			(at -0.25 0.45)
			(size 0.25 1)
			(layers "F.Cu" "F.Mask" "F.Paste")
			(roundrect_rratio 0.125)
			(net 23 "GND")
			(pinfunction "PGND")
			(pintype "power_in")
		)
		(pad "5" smd roundrect
			(at 0.925 0.5)
			(size 0.55 0.25)
			(layers "F.Cu" "F.Mask" "F.Paste")
			(roundrect_rratio 0.125)
			(net 40 "+5V")
			(pinfunction "V_{IN}")
			(pintype "power_in")
		)
		(pad "6" smd roundrect
			(at 0.925 0)
			(size 0.55 0.25)
			(layers "F.Cu" "F.Mask" "F.Paste")
			(roundrect_rratio 0.125)
			(net 40 "+5V")
			(pinfunction "V_{IN}")
			(pintype "passive")
		)
		(pad "7" smd roundrect
			(at 0.925 -0.5)
			(size 0.55 0.25)
			(layers "F.Cu" "F.Mask" "F.Paste")
			(roundrect_rratio 0.125)
			(net 302 "/X710 DCDC converters/1V88_BST")
			(pinfunction "BST")
			(pintype "passive")
		)
		(pad "8" smd roundrect
			(at 0.25 -0.3)
			(size 0.25 1.3)
			(layers "F.Cu" "F.Mask" "F.Paste")
			(roundrect_rratio 0.125)
			(net 241 "/X710 DCDC converters/1V88_SW")
			(pinfunction "SW")
			(pintype "power_out")
		)
		(pad "9" smd roundrect
			(at -0.25 -0.675)
			(size 0.25 0.55)
			(layers "F.Cu" "F.Mask" "F.Paste")
			(roundrect_rratio 0.125)
			(net 380 "/X710 DCDC converters/1V88_PG")
			(pinfunction "PG")
			(pintype "passive")
		)
	)
	(footprint "antmicro-footprints:C_0603_1608Metric_EIA"
		(layer "F.Cu")
		(at 151.850001 105.600002 90)
		(descr "Capacitor SMD 0603, IPC-7351 Density Level A")
		(tags "Capacitor 0603")
		(property "Reference" "C146"
			(at -17.849995 14.449998 90)
			(layer "F.SilkS")
			(effects
				(font
					(size 0.7 0.7)
					(thickness 0.15)
				)
			)
		)
		(property "Value" "C_22u_16V_0603"
			(at -1.42757 1.770288 90)
			(layer "F.Fab")
			(effects
				(font
					(size 0.7 0.7)
					(thickness 0.15)
				)
				(justify left bottom)
			)
		)
		(property "Datasheet" "https://product.samsungsem.com/mlcc/CL10A226MO7JZN.do"
			(at 0 0 90)
			(layer "F.Fab")
			(hide yes)
			(effects
				(font
					(size 1.27 1.27)
					(thickness 0.15)
				)
			)
		)
		(property "Description" "SMD Multilayer Ceramic Capacitor"
			(at 0 0 90)
			(layer "F.Fab")
			(hide yes)
			(effects
				(font
					(size 1.27 1.27)
					(thickness 0.15)
				)
			)
		)
		(property "MPN" "CL10A226MO7JZNC"
			(at 0 0 90)
			(unlocked yes)
			(layer "F.Fab")
			(hide yes)
			(effects
				(font
					(size 1 1)
					(thickness 0.15)
				)
			)
		)
		(property "Manufacturer" "Samsung Electro-Mechanics"
			(at 0 0 90)
			(unlocked yes)
			(layer "F.Fab")
			(hide yes)
			(effects
				(font
					(size 1 1)
					(thickness 0.15)
				)
			)
		)
		(property "License" "Apache-2.0"
			(at 0 0 90)
			(unlocked yes)
			(layer "F.Fab")
			(hide yes)
			(effects
				(font
					(size 1 1)
					(thickness 0.15)
				)
			)
		)
		(property "Author" "Antmicro"
			(at 0 0 90)
			(unlocked yes)
			(layer "F.Fab")
			(hide yes)
			(effects
				(font
					(size 1 1)
					(thickness 0.15)
				)
			)
		)
		(property "Val" "22u"
			(at 0 0 90)
			(unlocked yes)
			(layer "F.Fab")
			(hide yes)
			(effects
				(font
					(size 1 1)
					(thickness 0.15)
				)
			)
		)
		(property "Voltage" "16V"
			(at 0 0 90)
			(unlocked yes)
			(layer "F.Fab")
			(hide yes)
			(effects
				(font
					(size 1 1)
					(thickness 0.15)
				)
			)
		)
		(property "Dielectric" ""
			(at 0 0 90)
			(unlocked yes)
			(layer "F.Fab")
			(hide yes)
			(effects
				(font
					(size 1 1)
					(thickness 0.15)
				)
			)
		)
		(sheetname "/X710 DCDC converters/")
		(sheetfile "DCDC_converters_X710.kicad_sch")
		(attr smd)
		(fp_line
			(start -0.15 -0.55)
			(end 0.15 -0.55)
			(stroke
				(width 0.15)
				(type solid)
			)
			(layer "F.SilkS")
		)
		(fp_line
			(start -0.15 0.55)
			(end 0.15 0.55)
			(stroke
				(width 0.15)
				(type solid)
			)
			(layer "F.SilkS")
		)
		(fp_rect
			(start -1.25 -0.65)
			(end 1.25 0.65)
			(stroke
				(width 0.05)
				(type solid)
			)
			(fill no)
			(layer "F.CrtYd")
		)
		(fp_rect
			(start -0.8 -0.45)
			(end 0.8 0.45)
			(stroke
				(width 0.15)
				(type solid)
			)
			(fill no)
			(layer "F.Fab")
		)
		(fp_text user "${REFERENCE}"
			(at -1.682 3.895 90)
			(layer "F.Fab")
			(effects
				(font
					(size 0.7 0.7)
					(thickness 0.15)
				)
				(justify left bottom)
			)
		)
		(fp_text user "License: Apache-2.0"
			(at -1.682 5.895 90)
			(layer "F.Fab")
			(effects
				(font
					(size 0.7 0.7)
					(thickness 0.15)
				)
				(justify left bottom)
			)
		)
		(fp_text user "Author: Antmicro"
			(at -1.682 4.894 90)
			(layer "F.Fab")
			(effects
				(font
					(size 0.7 0.7)
					(thickness 0.15)
				)
				(justify left bottom)
			)
		)
		(pad "1" smd roundrect
			(at -0.7 0 90)
			(size 0.8 1.1)
			(layers "F.Cu" "F.Mask" "F.Paste")
			(roundrect_rratio 0.2)
			(net 23 "GND")
			(pintype "passive")
		)
		(pad "2" smd roundrect
			(at 0.7 0 90)
			(size 0.8 1.1)
			(layers "F.Cu" "F.Mask" "F.Paste")
			(roundrect_rratio 0.2)
			(net 338 "/X710 DCDC converters/+1V88_OUT")
			(pintype "passive")
		)
	)
	(footprint "antmicro-footprints:C_0603_1608Metric_EIA"
		(layer "F.Cu")
		(at 136.450002 105.600001 90)
		(descr "Capacitor SMD 0603, IPC-7351 Density Level A")
		(tags "Capacitor 0603")
		(property "Reference" "C145"
			(at -17.849995 16.849997 90)
			(layer "F.SilkS")
			(effects
				(font
					(size 0.7 0.7)
					(thickness 0.15)
				)
			)
		)
		(property "Value" "C_22u_16V_0603"
			(at -1.42757 1.770288 90)
			(layer "F.Fab")
			(effects
				(font
					(size 0.7 0.7)
					(thickness 0.15)
				)
				(justify left bottom)
			)
		)
		(property "Datasheet" "https://product.samsungsem.com/mlcc/CL10A226MO7JZN.do"
			(at 0 0 90)
			(layer "F.Fab")
			(hide yes)
			(effects
				(font
					(size 1.27 1.27)
					(thickness 0.15)
				)
			)
		)
		(property "Description" "SMD Multilayer Ceramic Capacitor"
			(at 0 0 90)
			(layer "F.Fab")
			(hide yes)
			(effects
				(font
					(size 1.27 1.27)
					(thickness 0.15)
				)
			)
		)
		(property "MPN" "CL10A226MO7JZNC"
			(at 0 0 90)
			(unlocked yes)
			(layer "F.Fab")
			(hide yes)
			(effects
				(font
					(size 1 1)
					(thickness 0.15)
				)
			)
		)
		(property "Manufacturer" "Samsung Electro-Mechanics"
			(at 0 0 90)
			(unlocked yes)
			(layer "F.Fab")
			(hide yes)
			(effects
				(font
					(size 1 1)
					(thickness 0.15)
				)
			)
		)
		(property "License" "Apache-2.0"
			(at 0 0 90)
			(unlocked yes)
			(layer "F.Fab")
			(hide yes)
			(effects
				(font
					(size 1 1)
					(thickness 0.15)
				)
			)
		)
		(property "Author" "Antmicro"
			(at 0 0 90)
			(unlocked yes)
			(layer "F.Fab")
			(hide yes)
			(effects
				(font
					(size 1 1)
					(thickness 0.15)
				)
			)
		)
		(property "Val" "22u"
			(at 0 0 90)
			(unlocked yes)
			(layer "F.Fab")
			(hide yes)
			(effects
				(font
					(size 1 1)
					(thickness 0.15)
				)
			)
		)
		(property "Voltage" "16V"
			(at 0 0 90)
			(unlocked yes)
			(layer "F.Fab")
			(hide yes)
			(effects
				(font
					(size 1 1)
					(thickness 0.15)
				)
			)
		)
		(property "Dielectric" ""
			(at 0 0 90)
			(unlocked yes)
			(layer "F.Fab")
			(hide yes)
			(effects
				(font
					(size 1 1)
					(thickness 0.15)
				)
			)
		)
		(sheetname "/X710 DCDC converters/")
		(sheetfile "DCDC_converters_X710.kicad_sch")
		(attr smd)
		(fp_line
			(start -0.15 -0.55)
			(end 0.15 -0.55)
			(stroke
				(width 0.15)
				(type solid)
			)
			(layer "F.SilkS")
		)
		(fp_line
			(start -0.15 0.55)
			(end 0.15 0.55)
			(stroke
				(width 0.15)
				(type solid)
			)
			(layer "F.SilkS")
		)
		(fp_rect
			(start -1.25 -0.65)
			(end 1.25 0.65)
			(stroke
				(width 0.05)
				(type solid)
			)
			(fill no)
			(layer "F.CrtYd")
		)
		(fp_rect
			(start -0.8 -0.45)
			(end 0.8 0.45)
			(stroke
				(width 0.15)
				(type solid)
			)
			(fill no)
			(layer "F.Fab")
		)
		(fp_text user "License: Apache-2.0"
			(at -1.682 5.895 90)
			(layer "F.Fab")
			(effects
				(font
					(size 0.7 0.7)
					(thickness 0.15)
				)
				(justify left bottom)
			)
		)
		(fp_text user "Author: Antmicro"
			(at -1.682 4.894 90)
			(layer "F.Fab")
			(effects
				(font
					(size 0.7 0.7)
					(thickness 0.15)
				)
				(justify left bottom)
			)
		)
		(fp_text user "${REFERENCE}"
			(at -1.682 3.895 90)
			(layer "F.Fab")
			(effects
				(font
					(size 0.7 0.7)
					(thickness 0.15)
				)
				(justify left bottom)
			)
		)
		(pad "1" smd roundrect
			(at -0.7 0 90)
			(size 0.8 1.1)
			(layers "F.Cu" "F.Mask" "F.Paste")
			(roundrect_rratio 0.2)
			(net 23 "GND")
			(pintype "passive")
		)
		(pad "2" smd roundrect
			(at 0.7 0 90)
			(size 0.8 1.1)
			(layers "F.Cu" "F.Mask" "F.Paste")
			(roundrect_rratio 0.2)
			(net 335 "/X710 DCDC converters/+VCCD_OUT")
			(pintype "passive")
		)
	)
	(footprint "antmicro-footprints:R_0603_1608Metric"
		(layer "F.Cu")
		(at 142.8 103.050002 90)
		(descr "Resistor SMD 0603")
		(tags "resistor SMD 0603")
		(property "Reference" "R112"
			(at -17.649996 15.649999 90)
			(layer "F.SilkS")
			(effects
				(font
					(size 0.7 0.7)
					(thickness 0.15)
				)
			)
		)
		(property "Value" "R_0R_22.4A_0603"
			(at 0 1.6 90)
			(layer "F.Fab")
			(effects
				(font
					(size 0.7 0.7)
					(thickness 0.15)
				)
				(justify left bottom)
			)
		)
		(property "Datasheet" "https://fscdn.rohm.com/en/products/databook/datasheet/passive/resistor/chip_resistor/pmr-jpw-e.pdf"
			(at 0 0 90)
			(layer "F.Fab")
			(hide yes)
			(effects
				(font
					(size 1.27 1.27)
					(thickness 0.15)
				)
			)
		)
		(property "Description" "SMD Chip Resistor"
			(at 0 0 90)
			(layer "F.Fab")
			(hide yes)
			(effects
				(font
					(size 1.27 1.27)
					(thickness 0.15)
				)
			)
		)
		(property "MPN" "PMR03EZPJ000"
			(at 0 0 90)
			(unlocked yes)
			(layer "F.Fab")
			(hide yes)
			(effects
				(font
					(size 1 1)
					(thickness 0.15)
				)
			)
		)
		(property "Manufacturer" "ROHM Semiconductor"
			(at 0 0 90)
			(unlocked yes)
			(layer "F.Fab")
			(hide yes)
			(effects
				(font
					(size 1 1)
					(thickness 0.15)
				)
			)
		)
		(property "Val" "0R"
			(at 0 0 90)
			(unlocked yes)
			(layer "F.Fab")
			(hide yes)
			(effects
				(font
					(size 1 1)
					(thickness 0.15)
				)
			)
		)
		(property "Max. Curr." "22.4A"
			(at 0 0 90)
			(unlocked yes)
			(layer "F.Fab")
			(hide yes)
			(effects
				(font
					(size 1 1)
					(thickness 0.15)
				)
			)
		)
		(property "Author" "Antmicro"
			(at 0 0 90)
			(unlocked yes)
			(layer "F.Fab")
			(hide yes)
			(effects
				(font
					(size 1 1)
					(thickness 0.15)
				)
			)
		)
		(property "License" "Apache-2.0"
			(at 0 0 90)
			(unlocked yes)
			(layer "F.Fab")
			(hide yes)
			(effects
				(font
					(size 1 1)
					(thickness 0.15)
				)
			)
		)
		(property "Tolerance" "template_tolerance"
			(at 0 0 90)
			(unlocked yes)
			(layer "F.Fab")
			(hide yes)
			(effects
				(font
					(size 1 1)
					(thickness 0.15)
				)
			)
		)
		(sheetname "/X710 DCDC converters/")
		(sheetfile "DCDC_converters_X710.kicad_sch")
		(attr smd)
		(fp_line
			(start -0.15 -0.4)
			(end 0.15 -0.4)
			(stroke
				(width 0.15)
				(type solid)
			)
			(layer "F.SilkS")
		)
		(fp_line
			(start -0.15 0.4)
			(end 0.15 0.4)
			(stroke
				(width 0.15)
				(type solid)
			)
			(layer "F.SilkS")
		)
		(fp_rect
			(start -1.25 -0.65)
			(end 1.25 0.65)
			(stroke
				(width 0.05)
				(type solid)
			)
			(fill no)
			(layer "F.CrtYd")
		)
		(fp_rect
			(start -0.8 -0.4)
			(end 0.8 0.4)
			(stroke
				(width 0.15)
				(type solid)
			)
			(fill no)
			(layer "F.Fab")
		)
		(fp_text user "${REFERENCE}"
			(at -1.25 3.898 90)
			(layer "F.Fab")
			(effects
				(font
					(size 0.7 0.7)
					(thickness 0.15)
				)
				(justify left bottom)
			)
		)
		(fp_text user "License: Apache-2.0"
			(at -1.25 5.9 90)
			(layer "F.Fab")
			(effects
				(font
					(size 0.7 0.7)
					(thickness 0.15)
				)
				(justify left bottom)
			)
		)
		(fp_text user "Author: Antmicro"
			(at -1.25 4.9 90)
			(layer "F.Fab")
			(effects
				(font
					(size 0.7 0.7)
					(thickness 0.15)
				)
				(justify left bottom)
			)
		)
		(pad "1" smd roundrect
			(at -0.7 0 90)
			(size 0.8 1)
			(layers "F.Cu" "F.Mask" "F.Paste")
			(roundrect_rratio 0.2)
			(net 341 "/X710 DCDC converters/+DVDD_OUT")
			(pintype "passive")
		)
		(pad "2" smd roundrect
			(at 0.7 0 90)
			(size 0.8 1)
			(layers "F.Cu" "F.Mask" "F.Paste")
			(roundrect_rratio 0.2)
			(net 6 "DVDD")
			(pintype "passive")
		)
	)
)
